(kicad_pcb
	(version 20221018)
	(generator pcbnew)
	(general
    (thickness 1.7403)
  )
	(paper "A4")
	(title_block
    (title "Data Center RDIMM DDR4 Tester")
    (date "2024-09-30")
    (rev "1.2.4")
		(comment 9 "footprint 168 of 690 (U15), pads 529-619 of 676")
	)
	(layers
    (0 "F.Cu" signal)
    (1 "In1.Cu" power)
    (2 "In2.Cu" signal)
    (3 "In3.Cu" power)
    (4 "In4.Cu" power)
    (5 "In5.Cu" signal)
    (6 "In6.Cu" power)
    (7 "In7.Cu" signal)
    (8 "In8.Cu" power)
    (9 "In9.Cu" signal)
    (10 "In10.Cu" power)
    (31 "B.Cu" signal)
    (32 "B.Adhes" user "B.Adhesive")
    (33 "F.Adhes" user "F.Adhesive")
    (34 "B.Paste" user)
    (35 "F.Paste" user)
    (36 "B.SilkS" user "B.Silkscreen")
    (37 "F.SilkS" user "F.Silkscreen")
    (38 "B.Mask" user)
    (39 "F.Mask" user)
    (40 "Dwgs.User" user "User.Drawings")
    (41 "Cmts.User" user "User.Comments")
    (42 "Eco1.User" user "User.Eco1")
    (43 "Eco2.User" user "User.Eco2")
    (44 "Edge.Cuts" user)
    (45 "Margin" user)
    (46 "B.CrtYd" user "B.Courtyard")
    (47 "F.CrtYd" user "F.Courtyard")
    (48 "B.Fab" user)
    (49 "F.Fab" user)
  )
	(footprint "data-center-rdimm-ddr4-tester-footprints:BGA-676_27x27mm_Layout26x26_P1X1mm"
    (layer "F.Cu")
    (at 183.635 90.06 180)
    (descr "FPGA XC7K160TFBG676")
    (tags "FPGA XC7K160TFBG676")
    (property "Author" "Antmicro")
    (property "License" "Apache-2.0")
    (property "MPN" "XC7K160T-FFG676")
    (property "Manufacturer" "AMD-Xilinx")
    (property "Sheetfile" "config-spi.kicad_sch")
    (property "Sheetname" "Config SPI flash")
    (property "ki_description" "Kintex®-7 Field Programmable Gate Array (FPGA) IC 300 4976640 65600 676-BBGA, FCBGA")
    (property "ki_keywords" "SMT, MICROCONTROLLER, IC, FPGA")
    (attr smd)
    (fp_text reference "U15" (at -10.675 -14.7 180) (layer "F.SilkS")
        (effects (font (size 0.7 0.7) (thickness 0.15)) (justify left bottom))
    )
    (fp_text value "XC7K160T-FFG676" (at 0 15.5 180) (layer "F.Fab")
        (effects (font (size 0.7 0.7) (thickness 0.15)) (justify left bottom))
    )
    (pad "R9" smd circle (at -4.5 1.499 180) (size 0.5 0.5) (layers "F.Cu" "F.Paste" "F.Mask")
      (net 144 "1V8_SYS") (pinfunction "VCCAUX_IO_G0") (pintype "passive"))
    (pad "R10" smd circle (at -3.5 1.499 180) (size 0.5 0.5) (layers "F.Cu" "F.Paste" "F.Mask")
      (net 9 "GND") (pinfunction "GND") (pintype "passive"))
    (pad "R11" smd circle (at -2.5 1.499 180) (size 0.5 0.5) (layers "F.Cu" "F.Paste" "F.Mask")
      (net 9 "GND") (pinfunction "DXN_0") (pintype "bidirectional") (die_length 14.9))
    (pad "R12" smd circle (at -1.5 1.499 180) (size 0.5 0.5) (layers "F.Cu" "F.Paste" "F.Mask")
      (net 9 "GND") (pinfunction "DXP_0") (pintype "bidirectional") (die_length 12.842))
    (pad "R13" smd circle (at -0.5 1.499 180) (size 0.5 0.5) (layers "F.Cu" "F.Paste" "F.Mask")
      (net 147 "1V0_SYS") (pinfunction "VCCBRAM") (pintype "passive"))
    (pad "R14" smd circle (at 0.499 1.499 180) (size 0.5 0.5) (layers "F.Cu" "F.Paste" "F.Mask")
      (net 9 "GND") (pinfunction "GND") (pintype "passive"))
    (pad "R15" smd circle (at 1.499 1.499 180) (size 0.5 0.5) (layers "F.Cu" "F.Paste" "F.Mask")
      (net 147 "1V0_SYS") (pinfunction "VCCINT") (pintype "passive"))
    (pad "R16" smd circle (at 2.499 1.499 180) (size 0.5 0.5) (layers "F.Cu" "F.Paste" "F.Mask")
      (net 347 "DQS17_P") (pinfunction "IO_L21P_T3_DQS_13") (pintype "bidirectional") (die_length 10.096))
    (pad "R17" smd circle (at 3.499 1.499 180) (size 0.5 0.5) (layers "F.Cu" "F.Paste" "F.Mask")
      (net 349 "DQS17_N") (pinfunction "IO_L21N_T3_DQS_13") (pintype "bidirectional") (die_length 10.012))
    (pad "R18" smd circle (at 4.499 1.499 180) (size 0.5 0.5) (layers "F.Cu" "F.Paste" "F.Mask")
      (net 867 "unconnected-(U15B-IO_L24P_T3_13-PadR18)") (pinfunction "IO_L24P_T3_13") (pintype "bidirectional+no_connect") (die_length 8.982))
    (pad "R19" smd circle (at 5.499 1.499 180) (size 0.5 0.5) (layers "F.Cu" "F.Paste" "F.Mask")
      (net 77 "VDDQ") (pinfunction "VCCO_13") (pintype "passive"))
    (pad "R20" smd circle (at 6.499 1.499 180) (size 0.5 0.5) (layers "F.Cu" "F.Paste" "F.Mask")
      (net 868 "unconnected-(U15B-IO_L16N_T2_13-PadR20)") (pinfunction "IO_L16N_T2_13") (pintype "bidirectional+no_connect") (die_length 9.979))
    (pad "R21" smd circle (at 7.499 1.499 180) (size 0.5 0.5) (layers "F.Cu" "F.Paste" "F.Mask")
      (net 259 "CB6") (pinfunction "IO_L13P_T2_MRCC_13") (pintype "bidirectional") (die_length 10.23))
    (pad "R22" smd circle (at 8.499 1.499 180) (size 0.5 0.5) (layers "F.Cu" "F.Paste" "F.Mask")
      (net 260 "CB2") (pinfunction "IO_L14P_T2_SRCC_13") (pintype "bidirectional") (die_length 11.973))
    (pad "R23" smd circle (at 9.499 1.499 180) (size 0.5 0.5) (layers "F.Cu" "F.Paste" "F.Mask")
      (net 869 "unconnected-(U15B-IO_L14N_T2_SRCC_13-PadR23)") (pinfunction "IO_L14N_T2_SRCC_13") (pintype "bidirectional+no_connect") (die_length 12.182))
    (pad "R24" smd circle (at 10.499 1.499 180) (size 0.5 0.5) (layers "F.Cu" "F.Paste" "F.Mask")
      (net 9 "GND") (pinfunction "GND") (pintype "passive"))
    (pad "R25" smd circle (at 11.499 1.499 180) (size 0.5 0.5) (layers "F.Cu" "F.Paste" "F.Mask")
      (net 870 "unconnected-(U15B-IO_L6P_T0_13-PadR25)") (pinfunction "IO_L6P_T0_13") (pintype "bidirectional+no_connect") (die_length 14.416))
    (pad "R26" smd circle (at 12.499 1.499 180) (size 0.5 0.5) (layers "F.Cu" "F.Paste" "F.Mask")
      (net 871 "unconnected-(U15B-IO_L2P_T0_13-PadR26)") (pinfunction "IO_L2P_T0_13") (pintype "bidirectional+no_connect") (die_length 16.3))
    (pad "T1" smd circle (at -12.5 2.499 180) (size 0.5 0.5) (layers "F.Cu" "F.Paste" "F.Mask")
      (net 9 "GND") (pinfunction "GND") (pintype "passive"))
    (pad "T2" smd circle (at -11.5 2.499 180) (size 0.5 0.5) (layers "F.Cu" "F.Paste" "F.Mask")
      (net 24 "MODE1") (pinfunction "M1_0") (pintype "bidirectional") (die_length 22.574))
    (pad "T3" smd circle (at -10.5 2.499 180) (size 0.5 0.5) (layers "F.Cu" "F.Paste" "F.Mask")
      (net 9 "GND") (pinfunction "GND") (pintype "passive"))
    (pad "T4" smd circle (at -9.5 2.499 180) (size 0.5 0.5) (layers "F.Cu" "F.Paste" "F.Mask")
      (net 9 "GND") (pinfunction "GND") (pintype "passive"))
    (pad "T5" smd circle (at -8.5 2.499 180) (size 0.5 0.5) (layers "F.Cu" "F.Paste" "F.Mask")
      (net 23 "MODE0") (pinfunction "M0_0") (pintype "bidirectional") (die_length 20.855))
    (pad "T6" smd circle (at -7.5 2.499 180) (size 0.5 0.5) (layers "F.Cu" "F.Paste" "F.Mask")
      (net 143 "3V3_SYS") (pinfunction "VCCO_0") (pintype "passive"))
    (pad "T7" smd circle (at -6.5 2.499 180) (size 0.5 0.5) (layers "F.Cu" "F.Paste" "F.Mask")
      (net 872 "unconnected-(U15H-IO_25_VRP_34-PadT7)") (pinfunction "IO_25_VRP_34") (pintype "bidirectional+no_connect") (die_length 9.857))
    (pad "T8" smd circle (at -5.5 2.499 180) (size 0.5 0.5) (layers "F.Cu" "F.Paste" "F.Mask")
      (net 144 "1V8_SYS") (pinfunction "VCCAUX_IO_G0") (pintype "passive"))
    (pad "T9" smd circle (at -4.5 2.499 180) (size 0.5 0.5) (layers "F.Cu" "F.Paste" "F.Mask")
      (net 9 "GND") (pinfunction "GND") (pintype "passive"))
    (pad "T10" smd circle (at -3.5 2.499 180) (size 0.5 0.5) (layers "F.Cu" "F.Paste" "F.Mask")
      (net 144 "1V8_SYS") (pinfunction "VCCAUX") (pintype "passive"))
    (pad "T11" smd circle (at -2.5 2.499 180) (size 0.5 0.5) (layers "F.Cu" "F.Paste" "F.Mask")
      (net 9 "GND") (pinfunction "GND") (pintype "passive"))
    (pad "T12" smd circle (at -1.5 2.499 180) (size 0.5 0.5) (layers "F.Cu" "F.Paste" "F.Mask")
      (net 147 "1V0_SYS") (pinfunction "VCCBRAM") (pintype "passive"))
    (pad "T13" smd circle (at -0.5 2.499 180) (size 0.5 0.5) (layers "F.Cu" "F.Paste" "F.Mask")
      (net 9 "GND") (pinfunction "GND") (pintype "passive"))
    (pad "T14" smd circle (at 0.499 2.499 180) (size 0.5 0.5) (layers "F.Cu" "F.Paste" "F.Mask")
      (net 147 "1V0_SYS") (pinfunction "VCCINT") (pintype "passive"))
    (pad "T15" smd circle (at 1.499 2.499 180) (size 0.5 0.5) (layers "F.Cu" "F.Paste" "F.Mask")
      (net 9 "GND") (pinfunction "GND") (pintype "passive"))
    (pad "T16" smd circle (at 2.499 2.499 180) (size 0.5 0.5) (layers "F.Cu" "F.Paste" "F.Mask")
      (net 77 "VDDQ") (pinfunction "VCCO_13") (pintype "passive"))
    (pad "T17" smd circle (at 3.499 2.499 180) (size 0.5 0.5) (layers "F.Cu" "F.Paste" "F.Mask")
      (net 257 "CB4") (pinfunction "IO_L23N_T3_13") (pintype "bidirectional") (die_length 10.353))
    (pad "T18" smd circle (at 4.499 2.499 180) (size 0.5 0.5) (layers "F.Cu" "F.Paste" "F.Mask")
      (net 258 "CB0") (pinfunction "IO_L19P_T3_13") (pintype "bidirectional") (die_length 9.92))
    (pad "T19" smd circle (at 5.499 2.499 180) (size 0.5 0.5) (layers "F.Cu" "F.Paste" "F.Mask")
      (net 873 "unconnected-(U15B-IO_L19N_T3_VREF_13-PadT19)") (pinfunction "IO_L19N_T3_VREF_13") (pintype "bidirectional+no_connect") (die_length 9.055))
    (pad "T20" smd circle (at 6.499 2.499 180) (size 0.5 0.5) (layers "F.Cu" "F.Paste" "F.Mask")
      (net 874 "unconnected-(U15B-IO_L16P_T2_13-PadT20)") (pinfunction "IO_L16P_T2_13") (pintype "bidirectional+no_connect") (die_length 9.491))
    (pad "T21" smd circle (at 7.499 2.499 180) (size 0.5 0.5) (layers "F.Cu" "F.Paste" "F.Mask")
      (net 9 "GND") (pinfunction "GND") (pintype "passive"))
    (pad "T22" smd circle (at 8.499 2.499 180) (size 0.5 0.5) (layers "F.Cu" "F.Paste" "F.Mask")
      (net 282 "CB7") (pinfunction "IO_L17P_T2_13") (pintype "bidirectional") (die_length 11.169))
    (pad "T23" smd circle (at 9.499 2.499 180) (size 0.5 0.5) (layers "F.Cu" "F.Paste" "F.Mask")
      (net 295 "CB3") (pinfunction "IO_L17N_T2_13") (pintype "bidirectional") (die_length 11.495))
    (pad "T24" smd circle (at 10.499 2.499 180) (size 0.5 0.5) (layers "F.Cu" "F.Paste" "F.Mask")
      (net 875 "unconnected-(U15B-IO_L15P_T2_DQS_13-PadT24)") (pinfunction "IO_L15P_T2_DQS_13") (pintype "bidirectional+no_connect") (die_length 13.293))
    (pad "T25" smd circle (at 11.499 2.499 180) (size 0.5 0.5) (layers "F.Cu" "F.Paste" "F.Mask")
      (net 876 "unconnected-(U15B-IO_L15N_T2_DQS_13-PadT25)") (pinfunction "IO_L15N_T2_DQS_13") (pintype "bidirectional+no_connect") (die_length 13.562))
    (pad "T26" smd circle (at 12.499 2.499 180) (size 0.5 0.5) (layers "F.Cu" "F.Paste" "F.Mask")
      (net 77 "VDDQ") (pinfunction "VCCO_13") (pintype "passive"))
    (pad "U1" smd circle (at -12.5 3.499 180) (size 0.5 0.5) (layers "F.Cu" "F.Paste" "F.Mask")
      (net 249 "DQ20") (pinfunction "IO_L2N_T0_34") (pintype "bidirectional") (die_length 17.749))
    (pad "U2" smd circle (at -11.5 3.499 180) (size 0.5 0.5) (layers "F.Cu" "F.Paste" "F.Mask")
      (net 246 "DQ8") (pinfunction "IO_L2P_T0_34") (pintype "bidirectional") (die_length 16.314))
    (pad "U3" smd circle (at -10.5 3.499 180) (size 0.5 0.5) (layers "F.Cu" "F.Paste" "F.Mask")
      (net 77 "VDDQ") (pinfunction "VCCO_34") (pintype "passive"))
    (pad "U4" smd circle (at -9.5 3.499 180) (size 0.5 0.5) (layers "F.Cu" "F.Paste" "F.Mask")
      (net 877 "unconnected-(U15H-IO_0_VRN_34-PadU4)") (pinfunction "IO_0_VRN_34") (pintype "bidirectional+no_connect") (die_length 17.697))
    (pad "U5" smd circle (at -8.5 3.499 180) (size 0.5 0.5) (layers "F.Cu" "F.Paste" "F.Mask")
      (net 242 "DQ0") (pinfunction "IO_L1N_T0_34") (pintype "bidirectional") (die_length 13.682))
    (pad "U6" smd circle (at -7.5 3.499 180) (size 0.5 0.5) (layers "F.Cu" "F.Paste" "F.Mask")
      (net 298 "DQ5") (pinfunction "IO_L1P_T0_34") (pintype "bidirectional") (die_length 13.683))
    (pad "U7" smd circle (at -6.5 3.499 180) (size 0.5 0.5) (layers "F.Cu" "F.Paste" "F.Mask")
      (net 241 "DQ4") (pinfunction "IO_L5P_T0_34") (pintype "bidirectional") (die_length 12.718))
    (pad "U8" smd circle (at -5.5 3.499 180) (size 0.5 0.5) (layers "F.Cu" "F.Paste" "F.Mask")
      (net 9 "GND") (pinfunction "GND") (pintype "passive"))
    (pad "U9" smd circle (at -4.5 3.499 180) (size 0.5 0.5) (layers "F.Cu" "F.Paste" "F.Mask")
      (net 309 "VRN") (pinfunction "IO_0_VRN_33") (pintype "bidirectional") (die_length 7.601))
    (pad "U10" smd circle (at -3.5 3.499 180) (size 0.5 0.5) (layers "F.Cu" "F.Paste" "F.Mask")
      (net 9 "GND") (pinfunction "GND") (pintype "passive"))
    (pad "U11" smd circle (at -2.5 3.499 180) (size 0.5 0.5) (layers "F.Cu" "F.Paste" "F.Mask")
      (net 144 "1V8_SYS") (pinfunction "VCCAUX") (pintype "passive"))
    (pad "U12" smd circle (at -1.5 3.499 180) (size 0.5 0.5) (layers "F.Cu" "F.Paste" "F.Mask")
      (net 9 "GND") (pinfunction "GND") (pintype "passive"))
    (pad "U13" smd circle (at -0.5 3.499 180) (size 0.5 0.5) (layers "F.Cu" "F.Paste" "F.Mask")
      (net 147 "1V0_SYS") (pinfunction "VCCBRAM") (pintype "passive"))
    (pad "U14" smd circle (at 0.499 3.499 180) (size 0.5 0.5) (layers "F.Cu" "F.Paste" "F.Mask")
      (net 9 "GND") (pinfunction "GND") (pintype "passive"))
    (pad "U15" smd circle (at 1.499 3.499 180) (size 0.5 0.5) (layers "F.Cu" "F.Paste" "F.Mask")
      (net 147 "1V0_SYS") (pinfunction "VCCINT") (pintype "passive"))
    (pad "U16" smd circle (at 2.499 3.499 180) (size 0.5 0.5) (layers "F.Cu" "F.Paste" "F.Mask")
      (net 278 "CB5") (pinfunction "IO_25_13") (pintype "bidirectional") (die_length 9.654))
    (pad "U17" smd circle (at 3.499 3.499 180) (size 0.5 0.5) (layers "F.Cu" "F.Paste" "F.Mask")
      (net 272 "CB1") (pinfunction "IO_L23P_T3_13") (pintype "bidirectional") (die_length 11.04))
    (pad "U18" smd circle (at 4.499 3.499 180) (size 0.5 0.5) (layers "F.Cu" "F.Paste" "F.Mask")
      (net 9 "GND") (pinfunction "GND") (pintype "passive"))
    (pad "U19" smd circle (at 5.499 3.499 180) (size 0.5 0.5) (layers "F.Cu" "F.Paste" "F.Mask")
      (net 878 "unconnected-(U15B-IO_L18P_T2_13-PadU19)") (pinfunction "IO_L18P_T2_13") (pintype "bidirectional+no_connect") (die_length 8.112))
    (pad "U20" smd circle (at 6.499 3.499 180) (size 0.5 0.5) (layers "F.Cu" "F.Paste" "F.Mask")
      (net 879 "unconnected-(U15B-IO_L18N_T2_13-PadU20)") (pinfunction "IO_L18N_T2_13") (pintype "bidirectional+no_connect") (die_length 9.928))
    (pad "U21" smd circle (at 7.499 3.499 180) (size 0.5 0.5) (layers "F.Cu" "F.Paste" "F.Mask")
      (net 880 "unconnected-(U15A-IO_0_12-PadU21)") (pinfunction "IO_0_12") (pintype "bidirectional+no_connect") (die_length 9.631))
    (pad "U22" smd circle (at 8.499 3.499 180) (size 0.5 0.5) (layers "F.Cu" "F.Paste" "F.Mask")
      (net 881 "unconnected-(U15A-IO_L1P_T0_12-PadU22)") (pinfunction "IO_L1P_T0_12") (pintype "bidirectional+no_connect") (die_length 10.705))
    (pad "U23" smd circle (at 9.499 3.499 180) (size 0.5 0.5) (layers "F.Cu" "F.Paste" "F.Mask")
      (net 143 "3V3_SYS") (pinfunction "VCCO_12") (pintype "passive"))
    (pad "U24" smd circle (at 10.499 3.499 180) (size 0.5 0.5) (layers "F.Cu" "F.Paste" "F.Mask")
      (net 796 "ETH_SEL") (pinfunction "IO_L2P_T0_12") (pintype "bidirectional") (die_length 12.37))
    (pad "U25" smd circle (at 11.499 3.499 180) (size 0.5 0.5) (layers "F.Cu" "F.Paste" "F.Mask")
      (net 37 "ETH_RXD3") (pinfunction "IO_L2N_T0_12") (pintype "bidirectional") (die_length 14.162))
    (pad "U26" smd circle (at 12.499 3.499 180) (size 0.5 0.5) (layers "F.Cu" "F.Paste" "F.Mask")
      (net 35 "ETH_TX_EN") (pinfunction "IO_L4P_T0_12") (pintype "bidirectional") (die_length 15.43))
    (pad "V1" smd circle (at -12.5 4.499 180) (size 0.5 0.5) (layers "F.Cu" "F.Paste" "F.Mask")
      (net 250 "DQ16") (pinfunction "IO_L8N_T1_34") (pintype "bidirectional") (die_length 17.73))
    (pad "V2" smd circle (at -11.5 4.499 180) (size 0.5 0.5) (layers "F.Cu" "F.Paste" "F.Mask")
      (net 294 "DQ21") (pinfunction "IO_L8P_T1_34") (pintype "bidirectional") (die_length 16.717))
    (pad "V3" smd circle (at -10.5 4.499 180) (size 0.5 0.5) (layers "F.Cu" "F.Paste" "F.Mask")
      (net 319 "DQS10_P") (pinfunction "IO_L4P_T0_34") (pintype "bidirectional") (die_length 16.996))
    (pad "V4" smd circle (at -9.5 4.499 180) (size 0.5 0.5) (layers "F.Cu" "F.Paste" "F.Mask")
      (net 275 "DQ13") (pinfunction "IO_L6P_T0_34") (pintype "bidirectional") (die_length 16.475))
    (pad "V5" smd circle (at -8.5 4.499 180) (size 0.5 0.5) (layers "F.Cu" "F.Paste" "F.Mask")
      (net 9 "GND") (pinfunction "GND") (pintype "passive"))
    (pad "V6" smd circle (at -7.5 4.499 180) (size 0.5 0.5) (layers "F.Cu" "F.Paste" "F.Mask")
      (net 288 "DQ1") (pinfunction "IO_L5N_T0_34") (pintype "bidirectional") (die_length 13.667))
    (pad "V7" smd circle (at -6.5 4.499 180) (size 0.5 0.5) (layers "F.Cu" "F.Paste" "F.Mask")
      (net 882 "unconnected-(U15G-IO_L2N_T0_33-PadV7)") (pinfunction "IO_L2N_T0_33") (pintype "bidirectional+no_connect") (die_length 12.123))
    (pad "V8" smd circle (at -5.5 4.499 180) (size 0.5 0.5) (layers "F.Cu" "F.Paste" "F.Mask")
      (net 889 "unconnected-(U15G-IO_L2P_T0_33-PadV8)") (pinfunction "IO_L2P_T0_33") (pintype "bidirectional+no_connect") (die_length 11.194))
    (pad "V9" smd circle (at -4.5 4.499 180) (size 0.5 0.5) (layers "F.Cu" "F.Paste" "F.Mask")
      (net 237 "~{CS0}") (pinfunction "IO_L6P_T0_33") (pintype "bidirectional") (die_length 10.483))
    (pad "V10" smd circle (at -3.5 4.499 180) (size 0.5 0.5) (layers "F.Cu" "F.Paste" "F.Mask")
      (net 77 "VDDQ") (pinfunction "VCCO_33") (pintype "passive"))
    (pad "V11" smd circle (at -2.5 4.499 180) (size 0.5 0.5) (layers "F.Cu" "F.Paste" "F.Mask")
      (net 230 "~{CS2}\\C0") (pinfunction "IO_L1P_T0_33") (pintype "bidirectional") (die_length 9.051))
    (pad "V12" smd circle (at -1.5 4.499 180) (size 0.5 0.5) (layers "F.Cu" "F.Paste" "F.Mask")
      (net 310 "VRP") (pinfunction "IO_25_VRP_33") (pintype "bidirectional") (die_length 8.364))
    (pad "V13" smd circle (at -0.5 4.499 180) (size 0.5 0.5) (layers "F.Cu" "F.Paste" "F.Mask")
      (net 890 "unconnected-(U15F-IO_0_VRN_32-PadV13)") (pinfunction "IO_0_VRN_32") (pintype "bidirectional+no_connect") (die_length 8.061))
    (pad "V14" smd circle (at 0.499 4.499 180) (size 0.5 0.5) (layers "F.Cu" "F.Paste" "F.Mask")
      (net 215 "DQ56") (pinfunction "IO_L24P_T3_32") (pintype "bidirectional") (die_length 12.558))
    (pad "V15" smd circle (at 1.499 4.499 180) (size 0.5 0.5) (layers "F.Cu" "F.Paste" "F.Mask")
      (net 9 "GND") (pinfunction "GND") (pintype "passive"))
    (pad "V16" smd circle (at 2.499 4.499 180) (size 0.5 0.5) (layers "F.Cu" "F.Paste" "F.Mask")
      (net 342 "DQS7_P") (pinfunction "IO_L20P_T3_32") (pintype "bidirectional") (die_length 18.47))
    (pad "V17" smd circle (at 3.499 4.499 180) (size 0.5 0.5) (layers "F.Cu" "F.Paste" "F.Mask")
      (net 344 "DQS7_N") (pinfunction "IO_L20N_T3_32") (pintype "bidirectional") (die_length 18.818))
    (pad "V18" smd circle (at 4.499 4.499 180) (size 0.5 0.5) (layers "F.Cu" "F.Paste" "F.Mask")
      (net 197 "DQ63") (pinfunction "IO_L23P_T3_32") (pintype "bidirectional") (die_length 17.507))
    (pad "V19" smd circle (at 5.499 4.499 180) (size 0.5 0.5) (layers "F.Cu" "F.Paste" "F.Mask")
      (net 196 "DQ59") (pinfunction "IO_L23N_T3_32") (pintype "bidirectional") (die_length 18.005))
    (pad "V20" smd circle (at 6.499 4.499 180) (size 0.5 0.5) (layers "F.Cu" "F.Paste" "F.Mask")
      (net 143 "3V3_SYS") (pinfunction "VCCO_12") (pintype "passive"))
    (pad "V21" smd circle (at 7.499 4.499 180) (size 0.5 0.5) (layers "F.Cu" "F.Paste" "F.Mask")
      (net 901 "unconnected-(U15A-IO_L6P_T0_12-PadV21)") (pinfunction "IO_L6P_T0_12") (pintype "bidirectional+no_connect") (die_length 8.805))
  )
)
